# S9S_MB_2U (Grand Teton) — schematic netlist excerpt (pin names and nets, part order shuffled) for the footprints in the layout excerpt that follows; sources: Cadence DE-HDL packaged netlist, KiCad conversion of 03242023_DA0F0TMBIJ0_F0T_Motherboard_J_brd_V01_OCP.brd

U143  PCA9545APW  IC  pkg TSSOP20_0-65_6-5X4-4  page 236
  A0  = PCA9543_S3M_ADDR0
  A1  = PCA9543_S3M_ADDR1
  \reset#\  = RST_SMB_S3M_N
  \int0#\  = PCA9543_S3M_INT0_N
  SD0  = SMB_S3M_CPU0_3V3AUX_SDA_R
  SC0  = SMB_S3M_CPU0_3V3AUX_SCL_R
  \int1#\  = PCA9543_S3M_INT1_N
  SD1  = SMB_S3M_CPU1_3V3AUX_SDA_R
  SC1  = SMB_S3M_CPU1_3V3AUX_SCL_R
  VSS  = GND
  \int2#\  = PCA9543_S3M_INT2_N
  SD2  = SMB_S3M_CPU0_PIROM_3V3AUX_SDA_R
  SC2  = SMB_S3M_CPU0_PIROM_3V3AUX_SCL_R
  \int3#\  = PCA9543_S3M_INT3_N
  SD3  = SMB_S3M_CPU1_PIROM_3V3AUX_SDA_R
  SC3  = SMB_S3M_CPU1_PIROM_3V3AUX_SCL_R
  \int#\  = PCA9545_S3M_INT_N
  SCL  = SMB_S3M_CPU_3V3AUX_SCL
  SDA  = SMB_S3M_CPU_3V3AUX_SDA
  VDD  = P3V3_AUX

(kicad_pcb
	(version 20260206)
	(generator "pcbnew")
	(generator_version "10.0")
	(general
		(thickness 1.6)
		(legacy_teardrops no)
	)
	(paper "A4")
	(title_block
		(title "03242023_DA0F0TMBIJ0_F0T_Motherboard_J_brd_V01_OCP.brd")
		(comment 1 "Grand Teton / footprints 1739-1739 of 6105")
	)
	(layers
		(0 "F.Cu" signal "TOP")
		(4 "In1.Cu" signal "GND")
		(6 "In2.Cu" signal "IN1")
		(8 "In3.Cu" signal "GND1")
		(10 "In4.Cu" signal "IN2")
		(12 "In5.Cu" signal "GND2")
		(14 "In6.Cu" signal "IN3")
		(16 "In7.Cu" signal "GND3")
		(18 "In8.Cu" signal "VCC")
		(20 "In9.Cu" signal "VCC1")
		(22 "In10.Cu" signal "GND4")
		(24 "In11.Cu" signal "IN4")
		(26 "In12.Cu" signal "GND5")
		(28 "In13.Cu" signal "IN5")
		(30 "In14.Cu" signal "GND6")
		(32 "In15.Cu" signal "IN6")
		(34 "In16.Cu" signal "GND7")
		(2 "B.Cu" signal "BOTTOM")
		(9 "F.Adhes" user "F.Adhesive")
		(11 "B.Adhes" user "B.Adhesive")
		(13 "F.Paste" user "Package Geometry/Pastemask Top")
		(15 "B.Paste" user "Package Geometry/Pastemask Bottom")
		(5 "F.SilkS" user "Ref Des/Silkscreen Top")
		(7 "B.SilkS" user "Ref Des/Silkscreen Bottom")
		(1 "F.Mask" user "Board Geometry/Soldermask Top")
		(3 "B.Mask" user "Board Geometry/Soldermask Bottom")
		(17 "Dwgs.User" user "User.Drawings")
		(19 "Cmts.User" user "User.Comments")
		(21 "Eco1.User" user "User.Eco1")
		(23 "Eco2.User" user "User.Eco2")
		(25 "Edge.Cuts" user "Board Geometry/Outline")
		(27 "Margin" user)
		(31 "F.CrtYd" user "Package Geometry/Place Bound Top")
		(29 "B.CrtYd" user "Package Geometry/Place Bound Bottom")
		(35 "F.Fab" user "Ref Des/Assembly Top")
		(33 "B.Fab" user "Ref Des/Assembly Bottom")
	)
	(footprint ""
		(layer "F.Cu")
		(at 155.136088 -76.244958 180)
		(property "Reference" "U143"
			(at -2.853944 -4.426712 0)
			(unlocked yes)
			(layer "F.SilkS")
			(effects
				(font
					(size 0.7874 0.5842)
					(thickness 0.1524)
				)
				(justify left)
			)
		)
		(property "Value" ""
			(at 0 0 180)
			(layer "F.Fab")
			(effects
				(font
					(size 1.27 1.27)
				)
			)
		)
		(duplicate_pad_numbers_are_jumpers no)
		(fp_line
			(start 2.161032 3.299968)
			(end -2.161032 3.299968)
			(stroke
				(width 0.1524)
				(type default)
			)
			(layer "F.SilkS")
		)
		(fp_line
			(start 2.161032 -3.299968)
			(end 2.161032 3.299968)
			(stroke
				(width 0.1524)
				(type default)
			)
			(layer "F.SilkS")
		)
		(fp_line
			(start 1.013968 -3.299968)
			(end 2.161032 -3.299968)
			(stroke
				(width 0.1524)
				(type default)
			)
			(layer "F.SilkS")
		)
		(fp_line
			(start 0 -2.54)
			(end 1.013968 -3.299968)
			(stroke
				(width 0.1524)
				(type default)
			)
			(layer "F.SilkS")
		)
		(fp_line
			(start -1.013968 -3.299968)
			(end 0 -2.54)
			(stroke
				(width 0.1524)
				(type default)
			)
			(layer "F.SilkS")
		)
		(fp_line
			(start -2.161032 3.299968)
			(end -2.161032 -3.299968)
			(stroke
				(width 0.1524)
				(type default)
			)
			(layer "F.SilkS")
		)
		(fp_line
			(start -2.161032 -3.299968)
			(end -1.013968 -3.299968)
			(stroke
				(width 0.1524)
				(type default)
			)
			(layer "F.SilkS")
		)
		(fp_poly
			(pts
				(xy -3.556 -2.925064) (xy -4.572 -2.417064) (xy -4.572 -3.433064)
			)
			(stroke
				(width 0)
				(type default)
			)
			(fill yes)
			(layer "F.SilkS")
		)
		(fp_line
			(start 2.249932 3.299968)
			(end 2.249932 -3.299968)
			(stroke
				(width 0.1)
				(type default)
			)
			(layer "F.Fab")
		)
		(fp_line
			(start 2.249932 -3.299968)
			(end -2.249932 -3.299968)
			(stroke
				(width 0.1)
				(type default)
			)
			(layer "F.Fab")
		)
		(fp_line
			(start -2.249932 3.299968)
			(end 2.249932 3.299968)
			(stroke
				(width 0.1)
				(type default)
			)
			(layer "F.Fab")
		)
		(fp_line
			(start -2.249932 -3.299968)
			(end -2.249932 3.299968)
			(stroke
				(width 0.1)
				(type default)
			)
			(layer "F.Fab")
		)
		(fp_poly
			(pts
				(xy -4.572 -3.433064) (xy -4.572 -2.417064) (xy -3.556 -2.925064)
			)
			(stroke
				(width 0)
				(type default)
			)
			(fill yes)
			(layer "F.Fab")
		)
		(pad "1" smd rect
			(at -2.84988 -2.925064 90)
			(size 0.4064 1.1176)
			(layers "F.Cu" "F.Mask" "F.Paste")
			(net "PCA9543_S3M_ADDR0")
		)
		(pad "2" smd rect
			(at -2.84988 -2.275078 90)
			(size 0.4064 1.1176)
			(layers "F.Cu" "F.Mask" "F.Paste")
			(net "PCA9543_S3M_ADDR1")
		)
		(pad "3" smd rect
			(at -2.84988 -1.625092 90)
			(size 0.4064 1.1176)
			(layers "F.Cu" "F.Mask" "F.Paste")
			(net "RST_SMB_S3M_N")
		)
		(pad "4" smd rect
			(at -2.84988 -0.975106 90)
			(size 0.4064 1.1176)
			(layers "F.Cu" "F.Mask" "F.Paste")
			(net "PCA9543_S3M_INT0_N")
		)
		(pad "5" smd rect
			(at -2.84988 -0.32512 90)
			(size 0.4064 1.1176)
			(layers "F.Cu" "F.Mask" "F.Paste")
			(net "SMB_S3M_CPU0_3V3AUX_SDA_R")
		)
		(pad "6" smd rect
			(at -2.84988 0.32512 90)
			(size 0.4064 1.1176)
			(layers "F.Cu" "F.Mask" "F.Paste")
			(net "SMB_S3M_CPU0_3V3AUX_SCL_R")
		)
		(pad "7" smd rect
			(at -2.84988 0.975106 90)
			(size 0.4064 1.1176)
			(layers "F.Cu" "F.Mask" "F.Paste")
			(net "PCA9543_S3M_INT1_N")
		)
		(pad "8" smd rect
			(at -2.84988 1.625092 90)
			(size 0.4064 1.1176)
			(layers "F.Cu" "F.Mask" "F.Paste")
			(net "SMB_S3M_CPU1_3V3AUX_SDA_R")
		)
		(pad "9" smd rect
			(at -2.84988 2.275078 90)
			(size 0.4064 1.1176)
			(layers "F.Cu" "F.Mask" "F.Paste")
			(net "SMB_S3M_CPU1_3V3AUX_SCL_R")
		)
		(pad "10" smd rect
			(at -2.84988 2.925064 90)
			(size 0.4064 1.1176)
			(layers "F.Cu" "F.Mask" "F.Paste")
			(net "GND")
		)
		(pad "11" smd rect
			(at 2.84988 2.925064 90)
			(size 0.4064 1.1176)
			(layers "F.Cu" "F.Mask" "F.Paste")
			(net "PCA9543_S3M_INT2_N")
		)
		(pad "12" smd rect
			(at 2.84988 2.275078 90)
			(size 0.4064 1.1176)
			(layers "F.Cu" "F.Mask" "F.Paste")
			(net "SMB_S3M_CPU0_PIROM_3V3AUX_SDA_R")
		)
		(pad "13" smd rect
			(at 2.84988 1.625092 90)
			(size 0.4064 1.1176)
			(layers "F.Cu" "F.Mask" "F.Paste")
			(net "SMB_S3M_CPU0_PIROM_3V3AUX_SCL_R")
		)
		(pad "14" smd rect
			(at 2.84988 0.975106 90)
			(size 0.4064 1.1176)
			(layers "F.Cu" "F.Mask" "F.Paste")
			(net "PCA9543_S3M_INT3_N")
		)
		(pad "15" smd rect
			(at 2.84988 0.32512 90)
			(size 0.4064 1.1176)
			(layers "F.Cu" "F.Mask" "F.Paste")
			(net "SMB_S3M_CPU1_PIROM_3V3AUX_SDA_R")
		)
		(pad "16" smd rect
			(at 2.84988 -0.32512 90)
			(size 0.4064 1.1176)
			(layers "F.Cu" "F.Mask" "F.Paste")
			(net "SMB_S3M_CPU1_PIROM_3V3AUX_SCL_R")
		)
		(pad "17" smd rect
			(at 2.84988 -0.975106 90)
			(size 0.4064 1.1176)
			(layers "F.Cu" "F.Mask" "F.Paste")
			(net "PCA9545_S3M_INT_N")
		)
		(pad "18" smd rect
			(at 2.84988 -1.625092 90)
			(size 0.4064 1.1176)
			(layers "F.Cu" "F.Mask" "F.Paste")
			(net "SMB_S3M_CPU_3V3AUX_SCL")
		)
		(pad "19" smd rect
			(at 2.84988 -2.275078 90)
			(size 0.4064 1.1176)
			(layers "F.Cu" "F.Mask" "F.Paste")
			(net "SMB_S3M_CPU_3V3AUX_SDA")
		)
		(pad "20" smd rect
			(at 2.84988 -2.925064 90)
			(size 0.4064 1.1176)
			(layers "F.Cu" "F.Mask" "F.Paste")
			(net "P3V3_AUX")
		)
	)
)
